# BASEBOARD_FAB2 (Tioga Pass) — schematic netlist excerpt (pin names and nets, part order shuffled) for the footprints in the layout excerpt that follows; sources: Cadence DE-HDL packaged netlist, KiCad conversion of Wiwynn_Tioga_Pass_MB.brd

R7F4  RES  33.2 1% CHIP  pkg 0402  page 153 : A = SPI_SWITCH_MISO ; B = SPI_MISO_R0
R8D21  RES  1.00K 1% CHIP  pkg 0402  page 135 : A = P3V3_STBY ; B = FM_IE_DISABLE_N
C1G16  CAP  220PF 50V 10% X7R  pkg 0402LF  page 223 : A = VR_PVDDQ_GHJ_AVSP ; B = VSENSE_PVDDQ_GHJ_N

(kicad_pcb
	(version 20260206)
	(generator "pcbnew")
	(generator_version "10.0")
	(general
		(thickness 1.6)
		(legacy_teardrops no)
	)
	(paper "A4")
	(title_block
		(title "Wiwynn_Tioga_Pass_MB.brd")
		(comment 1 "Tioga Pass / footprints 376-378 of 4770")
	)
	(layers
		(0 "F.Cu" signal "TOP")
		(4 "In1.Cu" signal "L2GND")
		(6 "In2.Cu" signal "L3")
		(8 "In3.Cu" signal "L4GND")
		(10 "In4.Cu" signal "L5")
		(12 "In5.Cu" signal "L6GND")
		(14 "In6.Cu" signal "L7VCC")
		(16 "In7.Cu" signal "L8VCC")
		(18 "In8.Cu" signal "L9GND")
		(20 "In9.Cu" signal "L10")
		(22 "In10.Cu" signal "L11GND")
		(24 "In11.Cu" signal "L12")
		(26 "In12.Cu" signal "L13GND")
		(2 "B.Cu" signal "BOTTOM")
		(9 "F.Adhes" user "F.Adhesive")
		(11 "B.Adhes" user "B.Adhesive")
		(13 "F.Paste" user "Package Geometry/Pastemask Top")
		(15 "B.Paste" user "Package Geometry/Pastemask Bottom")
		(5 "F.SilkS" user "Ref Des/Silkscreen Top")
		(7 "B.SilkS" user "Ref Des/Silkscreen Bottom")
		(1 "F.Mask" user "Board Geometry/Soldermask Top")
		(3 "B.Mask" user "Board Geometry/Soldermask Bottom")
		(17 "Dwgs.User" user "User.Drawings")
		(19 "Cmts.User" user "User.Comments")
		(21 "Eco1.User" user "User.Eco1")
		(23 "Eco2.User" user "User.Eco2")
		(25 "Edge.Cuts" user "Board Geometry/Outline")
		(27 "Margin" user)
		(31 "F.CrtYd" user "Package Geometry/Place Bound Top")
		(29 "B.CrtYd" user "Package Geometry/Place Bound Bottom")
		(35 "F.Fab" user "Ref Des/Assembly Top")
		(33 "B.Fab" user "Ref Des/Assembly Bottom")
	)
	(footprint ""
		(layer "F.Cu")
		(at 436.794402 -0.821182 -90)
		(property "Reference" "R8D21"
			(at 0 0 270)
			(layer "F.SilkS")
			(hide yes)
			(effects
				(font
					(size 1.27 1.27)
				)
			)
		)
		(property "Value" ""
			(at 0 0 270)
			(layer "F.Fab")
			(effects
				(font
					(size 1.27 1.27)
				)
			)
		)
		(duplicate_pad_numbers_are_jumpers no)
		(fp_poly
			(pts
				(xy -0.2794 -0.1016) (xy 0.2794 -0.1016) (xy 0.2794 0.9906) (xy -0.2794 0.9906)
			)
			(stroke
				(width 0)
				(type default)
			)
			(fill no)
			(layer "F.CrtYd")
		)
		(fp_line
			(start -0.2794 0.9906)
			(end 0.2794 0.9906)
			(stroke
				(width 0.1)
				(type default)
			)
			(layer "F.Fab")
		)
		(fp_line
			(start 0.2794 0.9906)
			(end 0.2794 -0.1016)
			(stroke
				(width 0.1)
				(type default)
			)
			(layer "F.Fab")
		)
		(fp_line
			(start -0.2794 -0.1016)
			(end -0.2794 0.9906)
			(stroke
				(width 0.1)
				(type default)
			)
			(layer "F.Fab")
		)
		(fp_line
			(start 0.2794 -0.1016)
			(end -0.2794 -0.1016)
			(stroke
				(width 0.1)
				(type default)
			)
			(layer "F.Fab")
		)
		(pad "1" smd rect
			(at 0 0 270)
			(size 0.508 0.508)
			(layers "F.Cu" "F.Mask" "F.Paste")
			(net "P3V3_STBY")
		)
		(pad "2" smd rect
			(at 0 0.889 270)
			(size 0.508 0.508)
			(layers "F.Cu" "F.Mask" "F.Paste")
			(net "FM_IE_DISABLE_N")
		)
		(zone
			(layer "F.Cu")
			(hatch none 0.5)
			(connect_pads
				(clearance 0)
			)
			(min_thickness 0.25)
			(keepout
				(tracks not_allowed)
				(vias allowed)
				(pads allowed)
				(copperpour not_allowed)
				(footprints allowed)
			)
			(placement
				(enabled no)
				(sheetname "")
			)
			(fill
				(thermal_gap 0.5)
				(thermal_bridge_width 0.5)
				(island_removal_mode 0)
			)
			(polygon
				(pts
					(xy 436.159402 -1.075182) (xy 436.159402 -0.567182) (xy 436.540402 -0.567182) (xy 436.540402 -1.075182)
				)
			)
		)
		(zone
			(layer "F.Cu")
			(hatch none 0.5)
			(connect_pads
				(clearance 0)
			)
			(min_thickness 0.25)
			(keepout
				(tracks allowed)
				(vias not_allowed)
				(pads allowed)
				(copperpour not_allowed)
				(footprints allowed)
			)
			(placement
				(enabled no)
				(sheetname "")
			)
			(fill
				(thermal_gap 0.5)
				(thermal_bridge_width 0.5)
				(island_removal_mode 0)
			)
			(polygon
				(pts
					(xy 436.540402 -1.075182) (xy 436.540402 -0.567182) (xy 436.159402 -0.567182) (xy 436.159402 -1.075182)
				)
			)
		)
	)
	(footprint ""
		(layer "F.Cu")
		(at 401.7518 -54.80558 -90)
		(property "Reference" "R7F4"
			(at 0 0 270)
			(layer "F.SilkS")
			(hide yes)
			(effects
				(font
					(size 1.27 1.27)
				)
			)
		)
		(property "Value" ""
			(at 0 0 270)
			(layer "F.Fab")
			(effects
				(font
					(size 1.27 1.27)
				)
			)
		)
		(duplicate_pad_numbers_are_jumpers no)
		(fp_poly
			(pts
				(xy -0.2794 -0.1016) (xy 0.2794 -0.1016) (xy 0.2794 0.9906) (xy -0.2794 0.9906)
			)
			(stroke
				(width 0)
				(type default)
			)
			(fill no)
			(layer "F.CrtYd")
		)
		(fp_line
			(start -0.2794 0.9906)
			(end 0.2794 0.9906)
			(stroke
				(width 0.1)
				(type default)
			)
			(layer "F.Fab")
		)
		(fp_line
			(start 0.2794 0.9906)
			(end 0.2794 -0.1016)
			(stroke
				(width 0.1)
				(type default)
			)
			(layer "F.Fab")
		)
		(fp_line
			(start -0.2794 -0.1016)
			(end -0.2794 0.9906)
			(stroke
				(width 0.1)
				(type default)
			)
			(layer "F.Fab")
		)
		(fp_line
			(start 0.2794 -0.1016)
			(end -0.2794 -0.1016)
			(stroke
				(width 0.1)
				(type default)
			)
			(layer "F.Fab")
		)
		(pad "1" smd rect
			(at 0 0 270)
			(size 0.508 0.508)
			(layers "F.Cu" "F.Mask" "F.Paste")
			(net "SPI_SWITCH_MISO")
		)
		(pad "2" smd rect
			(at 0 0.889 270)
			(size 0.508 0.508)
			(layers "F.Cu" "F.Mask" "F.Paste")
			(net "SPI_MISO_R0")
		)
		(zone
			(layer "F.Cu")
			(hatch none 0.5)
			(connect_pads
				(clearance 0)
			)
			(min_thickness 0.25)
			(keepout
				(tracks not_allowed)
				(vias allowed)
				(pads allowed)
				(copperpour not_allowed)
				(footprints allowed)
			)
			(placement
				(enabled no)
				(sheetname "")
			)
			(fill
				(thermal_gap 0.5)
				(thermal_bridge_width 0.5)
				(island_removal_mode 0)
			)
			(polygon
				(pts
					(xy 401.1168 -55.05958) (xy 401.1168 -54.55158) (xy 401.4978 -54.55158) (xy 401.4978 -55.05958)
				)
			)
		)
		(zone
			(layer "F.Cu")
			(hatch none 0.5)
			(connect_pads
				(clearance 0)
			)
			(min_thickness 0.25)
			(keepout
				(tracks allowed)
				(vias not_allowed)
				(pads allowed)
				(copperpour not_allowed)
				(footprints allowed)
			)
			(placement
				(enabled no)
				(sheetname "")
			)
			(fill
				(thermal_gap 0.5)
				(thermal_bridge_width 0.5)
				(island_removal_mode 0)
			)
			(polygon
				(pts
					(xy 401.4978 -55.05958) (xy 401.4978 -54.55158) (xy 401.1168 -54.55158) (xy 401.1168 -55.05958)
				)
			)
		)
	)
	(footprint ""
		(layer "F.Cu")
		(at 8.026146 -3.659886 -90)
		(property "Reference" "C1G16"
			(at 0 0 270)
			(layer "F.SilkS")
			(hide yes)
			(effects
				(font
					(size 1.27 1.27)
				)
			)
		)
		(property "Value" ""
			(at 0 0 270)
			(layer "F.Fab")
			(effects
				(font
					(size 1.27 1.27)
				)
			)
		)
		(duplicate_pad_numbers_are_jumpers no)
		(fp_rect
			(start -0.3048 0.9906)
			(end 0.3048 -0.1016)
			(stroke
				(width 0)
				(type default)
			)
			(fill no)
			(layer "F.CrtYd")
		)
		(fp_line
			(start -0.3048 0.9906)
			(end 0.3048 0.9906)
			(stroke
				(width 0.1)
				(type default)
			)
			(layer "F.Fab")
		)
		(fp_line
			(start 0.3048 0.9906)
			(end 0.3048 -0.1016)
			(stroke
				(width 0.1)
				(type default)
			)
			(layer "F.Fab")
		)
		(fp_line
			(start -0.3048 -0.1016)
			(end -0.3048 0.9906)
			(stroke
				(width 0.1)
				(type default)
			)
			(layer "F.Fab")
		)
		(fp_line
			(start 0.3048 -0.1016)
			(end -0.3048 -0.1016)
			(stroke
				(width 0.1)
				(type default)
			)
			(layer "F.Fab")
		)
		(pad "1" smd rect
			(at 0 0 270)
			(size 0.508 0.508)
			(layers "F.Cu" "F.Mask" "F.Paste")
			(net "VR_PVDDQ_GHJ_AVSP")
		)
		(pad "2" smd rect
			(at 0 0.889 270)
			(size 0.508 0.508)
			(layers "F.Cu" "F.Mask" "F.Paste")
			(net "VSENSE_PVDDQ_GHJ_N")
		)
		(zone
			(layer "F.Cu")
			(hatch none 0.5)
			(connect_pads
				(clearance 0)
			)
			(min_thickness 0.25)
			(keepout
				(tracks allowed)
				(vias not_allowed)
				(pads allowed)
				(copperpour not_allowed)
				(footprints allowed)
			)
			(placement
				(enabled no)
				(sheetname "")
			)
			(fill
				(thermal_gap 0.5)
				(thermal_bridge_width 0.5)
				(island_removal_mode 0)
			)
			(polygon
				(pts
					(xy 7.391146 -3.913886) (xy 7.391146 -3.405886) (xy 7.772146 -3.405886) (xy 7.772146 -3.913886)
				)
			)
		)
		(zone
			(layer "F.Cu")
			(hatch none 0.5)
			(connect_pads
				(clearance 0)
			)
			(min_thickness 0.25)
			(keepout
				(tracks not_allowed)
				(vias allowed)
				(pads allowed)
				(copperpour not_allowed)
				(footprints allowed)
			)
			(placement
				(enabled no)
				(sheetname "")
			)
			(fill
				(thermal_gap 0.5)
				(thermal_bridge_width 0.5)
				(island_removal_mode 0)
			)
			(polygon
				(pts
					(xy 7.391146 -3.913886) (xy 7.391146 -3.405886) (xy 7.772146 -3.405886) (xy 7.772146 -3.913886)
				)
			)
		)
	)
)
